(kicad_pcb
	(version 20260206)
	(generator "pcbnew")
	(generator_version "10.0")
	(general
		(thickness 1.6)
		(legacy_teardrops no)
	)
	(paper "A4")
	(title_block
		(title "Wiwynn_Tioga_Pass_MB.brd")
		(comment 1 "Tioga Pass / footprint 2096 of 4770 (J4A2), pads 1-123 of 291")
	)
	(layers
		(0 "F.Cu" signal "TOP")
		(4 "In1.Cu" signal "L2GND")
		(6 "In2.Cu" signal "L3")
		(8 "In3.Cu" signal "L4GND")
		(10 "In4.Cu" signal "L5")
		(12 "In5.Cu" signal "L6GND")
		(14 "In6.Cu" signal "L7VCC")
		(16 "In7.Cu" signal "L8VCC")
		(18 "In8.Cu" signal "L9GND")
		(20 "In9.Cu" signal "L10")
		(22 "In10.Cu" signal "L11GND")
		(24 "In11.Cu" signal "L12")
		(26 "In12.Cu" signal "L13GND")
		(2 "B.Cu" signal "BOTTOM")
		(9 "F.Adhes" user "F.Adhesive")
		(11 "B.Adhes" user "B.Adhesive")
		(13 "F.Paste" user "Package Geometry/Pastemask Top")
		(15 "B.Paste" user "Package Geometry/Pastemask Bottom")
		(5 "F.SilkS" user "Ref Des/Silkscreen Top")
		(7 "B.SilkS" user "Ref Des/Silkscreen Bottom")
		(1 "F.Mask" user "Board Geometry/Soldermask Top")
		(3 "B.Mask" user "Board Geometry/Soldermask Bottom")
		(17 "Dwgs.User" user "User.Drawings")
		(19 "Cmts.User" user "User.Comments")
		(21 "Eco1.User" user "User.Eco1")
		(23 "Eco2.User" user "User.Eco2")
		(25 "Edge.Cuts" user "Board Geometry/Outline")
		(27 "Margin" user)
		(31 "F.CrtYd" user "Package Geometry/Place Bound Top")
		(29 "B.CrtYd" user "Package Geometry/Place Bound Bottom")
		(35 "F.Fab" user "Ref Des/Assembly Top")
		(33 "B.Fab" user "Ref Des/Assembly Bottom")
	)
	(footprint ""
		(layer "F.Cu")
		(at 194.700398 -142.6718 90)
		(property "Reference" "J4A2"
			(at -2.369312 42.66311 0)
			(unlocked yes)
			(layer "F.SilkS")
			(effects
				(font
					(size 0.7874 0.5842)
					(thickness 0.1524)
				)
				(justify left)
			)
		)
		(property "Value" ""
			(at 0 0 90)
			(layer "F.Fab")
			(effects
				(font
					(size 1.27 1.27)
				)
			)
		)
		(duplicate_pad_numbers_are_jumpers no)
		(pad "" thru_hole circle
			(at 2.29997 -5.649976 90)
			(size 2.8194 2.8194)
			(drill 2.4384)
			(layers "*.Cu" "*.Mask")
			(remove_unused_layers no)
			(clearance 0.127)
			(thermal_gap 0.127)
		)
		(pad "" thru_hole oval
			(at 2.29997 68.90004 90)
			(size 2.8194 1.5748)
			(drill oval 2.4384 1.1938)
			(layers "*.Cu" "*.Mask")
			(remove_unused_layers no)
			(clearance 0.127)
			(thermal_gap 0.127)
		)
		(pad "" thru_hole circle
			(at 2.29997 132.299964 90)
			(size 2.8194 2.8194)
			(drill 2.4384)
			(layers "*.Cu" "*.Mask")
			(remove_unused_layers no)
			(clearance 0.127)
			(thermal_gap 0.127)
		)
		(pad "1" smd rect
			(at 0 0 90)
			(size 1.8034 0.508)
			(layers "F.Cu" "F.Mask" "F.Paste")
			(net "P12V_NVDIMM_DEF")
		)
		(pad "2" smd rect
			(at 0 0.849884 90)
			(size 1.8034 0.508)
			(layers "F.Cu" "F.Mask" "F.Paste")
			(net "GND")
		)
		(pad "3" smd rect
			(at 0 1.700022 90)
			(size 1.8034 0.508)
			(layers "F.Cu" "F.Mask" "F.Paste")
			(net "M_E_DQ<5>")
		)
		(pad "4" smd rect
			(at 0 2.549906 90)
			(size 1.8034 0.508)
			(layers "F.Cu" "F.Mask" "F.Paste")
			(net "GND")
		)
		(pad "5" smd rect
			(at 0 3.400044 90)
			(size 1.8034 0.508)
			(layers "F.Cu" "F.Mask" "F.Paste")
			(net "M_E_DQ<1>")
		)
		(pad "6" smd rect
			(at 0 4.249928 90)
			(size 1.8034 0.508)
			(layers "F.Cu" "F.Mask" "F.Paste")
			(net "GND")
		)
		(pad "7" smd rect
			(at 0 5.100066 90)
			(size 1.8034 0.508)
			(layers "F.Cu" "F.Mask" "F.Paste")
			(net "M_E_DQS_DP<9>")
		)
		(pad "8" smd rect
			(at 0 5.94995 90)
			(size 1.8034 0.508)
			(layers "F.Cu" "F.Mask" "F.Paste")
			(net "M_E_DQS_DN<9>")
		)
		(pad "9" smd rect
			(at 0 6.800088 90)
			(size 1.8034 0.508)
			(layers "F.Cu" "F.Mask" "F.Paste")
			(net "GND")
		)
		(pad "10" smd rect
			(at 0 7.649972 90)
			(size 1.8034 0.508)
			(layers "F.Cu" "F.Mask" "F.Paste")
			(net "M_E_DQ<7>")
		)
		(pad "11" smd rect
			(at 0 8.50011 90)
			(size 1.8034 0.508)
			(layers "F.Cu" "F.Mask" "F.Paste")
			(net "GND")
		)
		(pad "12" smd rect
			(at 0 9.349994 90)
			(size 1.8034 0.508)
			(layers "F.Cu" "F.Mask" "F.Paste")
			(net "M_E_DQ<3>")
		)
		(pad "13" smd rect
			(at 0 10.199878 90)
			(size 1.8034 0.508)
			(layers "F.Cu" "F.Mask" "F.Paste")
			(net "GND")
		)
		(pad "14" smd rect
			(at 0 11.050016 90)
			(size 1.8034 0.508)
			(layers "F.Cu" "F.Mask" "F.Paste")
			(net "M_E_DQ<13>")
		)
		(pad "15" smd rect
			(at 0 11.8999 90)
			(size 1.8034 0.508)
			(layers "F.Cu" "F.Mask" "F.Paste")
			(net "GND")
		)
		(pad "16" smd rect
			(at 0 12.750038 90)
			(size 1.8034 0.508)
			(layers "F.Cu" "F.Mask" "F.Paste")
			(net "M_E_DQ<9>")
		)
		(pad "17" smd rect
			(at 0 13.599922 90)
			(size 1.8034 0.508)
			(layers "F.Cu" "F.Mask" "F.Paste")
			(net "GND")
		)
		(pad "18" smd rect
			(at 0 14.45006 90)
			(size 1.8034 0.508)
			(layers "F.Cu" "F.Mask" "F.Paste")
			(net "M_E_DQS_DP<10>")
		)
		(pad "19" smd rect
			(at 0 15.299944 90)
			(size 1.8034 0.508)
			(layers "F.Cu" "F.Mask" "F.Paste")
			(net "M_E_DQS_DN<10>")
		)
		(pad "20" smd rect
			(at 0 16.150082 90)
			(size 1.8034 0.508)
			(layers "F.Cu" "F.Mask" "F.Paste")
			(net "GND")
		)
		(pad "21" smd rect
			(at 0 16.999966 90)
			(size 1.8034 0.508)
			(layers "F.Cu" "F.Mask" "F.Paste")
			(net "M_E_DQ<15>")
		)
		(pad "22" smd rect
			(at 0 17.850104 90)
			(size 1.8034 0.508)
			(layers "F.Cu" "F.Mask" "F.Paste")
			(net "GND")
		)
		(pad "23" smd rect
			(at 0 18.699988 90)
			(size 1.8034 0.508)
			(layers "F.Cu" "F.Mask" "F.Paste")
			(net "M_E_DQ<11>")
		)
		(pad "24" smd rect
			(at 0 19.550126 90)
			(size 1.8034 0.508)
			(layers "F.Cu" "F.Mask" "F.Paste")
			(net "GND")
		)
		(pad "25" smd rect
			(at 0 20.40001 90)
			(size 1.8034 0.508)
			(layers "F.Cu" "F.Mask" "F.Paste")
			(net "M_E_DQ<21>")
		)
		(pad "26" smd rect
			(at 0 21.249894 90)
			(size 1.8034 0.508)
			(layers "F.Cu" "F.Mask" "F.Paste")
			(net "GND")
		)
		(pad "27" smd rect
			(at 0 22.100032 90)
			(size 1.8034 0.508)
			(layers "F.Cu" "F.Mask" "F.Paste")
			(net "M_E_DQ<17>")
		)
		(pad "28" smd rect
			(at 0 22.949916 90)
			(size 1.8034 0.508)
			(layers "F.Cu" "F.Mask" "F.Paste")
			(net "GND")
		)
		(pad "29" smd rect
			(at 0 23.800054 90)
			(size 1.8034 0.508)
			(layers "F.Cu" "F.Mask" "F.Paste")
			(net "M_E_DQS_DP<11>")
		)
		(pad "30" smd rect
			(at 0 24.649938 90)
			(size 1.8034 0.508)
			(layers "F.Cu" "F.Mask" "F.Paste")
			(net "M_E_DQS_DN<11>")
		)
		(pad "31" smd rect
			(at 0 25.500076 90)
			(size 1.8034 0.508)
			(layers "F.Cu" "F.Mask" "F.Paste")
			(net "GND")
		)
		(pad "32" smd rect
			(at 0 26.34996 90)
			(size 1.8034 0.508)
			(layers "F.Cu" "F.Mask" "F.Paste")
			(net "M_E_DQ<23>")
		)
		(pad "33" smd rect
			(at 0 27.200098 90)
			(size 1.8034 0.508)
			(layers "F.Cu" "F.Mask" "F.Paste")
			(net "GND")
		)
		(pad "34" smd rect
			(at 0 28.049982 90)
			(size 1.8034 0.508)
			(layers "F.Cu" "F.Mask" "F.Paste")
			(net "M_E_DQ<19>")
		)
		(pad "35" smd rect
			(at 0 28.90012 90)
			(size 1.8034 0.508)
			(layers "F.Cu" "F.Mask" "F.Paste")
			(net "GND")
		)
		(pad "36" smd rect
			(at 0 29.750004 90)
			(size 1.8034 0.508)
			(layers "F.Cu" "F.Mask" "F.Paste")
			(net "M_E_DQ<29>")
		)
		(pad "37" smd rect
			(at 0 30.599888 90)
			(size 1.8034 0.508)
			(layers "F.Cu" "F.Mask" "F.Paste")
			(net "GND")
		)
		(pad "38" smd rect
			(at 0 31.450026 90)
			(size 1.8034 0.508)
			(layers "F.Cu" "F.Mask" "F.Paste")
			(net "M_E_DQ<25>")
		)
		(pad "39" smd rect
			(at 0 32.29991 90)
			(size 1.8034 0.508)
			(layers "F.Cu" "F.Mask" "F.Paste")
			(net "GND")
		)
		(pad "40" smd rect
			(at 0 33.150048 90)
			(size 1.8034 0.508)
			(layers "F.Cu" "F.Mask" "F.Paste")
			(net "M_E_DQS_DP<12>")
		)
		(pad "41" smd rect
			(at 0 33.999932 90)
			(size 1.8034 0.508)
			(layers "F.Cu" "F.Mask" "F.Paste")
			(net "M_E_DQS_DN<12>")
		)
		(pad "42" smd rect
			(at 0 34.85007 90)
			(size 1.8034 0.508)
			(layers "F.Cu" "F.Mask" "F.Paste")
			(net "GND")
		)
		(pad "43" smd rect
			(at 0 35.699954 90)
			(size 1.8034 0.508)
			(layers "F.Cu" "F.Mask" "F.Paste")
			(net "M_E_DQ<31>")
		)
		(pad "44" smd rect
			(at 0 36.550092 90)
			(size 1.8034 0.508)
			(layers "F.Cu" "F.Mask" "F.Paste")
			(net "GND")
		)
		(pad "45" smd rect
			(at 0 37.399976 90)
			(size 1.8034 0.508)
			(layers "F.Cu" "F.Mask" "F.Paste")
			(net "M_E_DQ<27>")
		)
		(pad "46" smd rect
			(at 0 38.250114 90)
			(size 1.8034 0.508)
			(layers "F.Cu" "F.Mask" "F.Paste")
			(net "GND")
		)
		(pad "47" smd rect
			(at 0 39.099998 90)
			(size 1.8034 0.508)
			(layers "F.Cu" "F.Mask" "F.Paste")
			(net "M_E_ECC<5>")
		)
		(pad "48" smd rect
			(at 0 39.949882 90)
			(size 1.8034 0.508)
			(layers "F.Cu" "F.Mask" "F.Paste")
			(net "GND")
		)
		(pad "49" smd rect
			(at 0 40.80002 90)
			(size 1.8034 0.508)
			(layers "F.Cu" "F.Mask" "F.Paste")
			(net "M_E_ECC<1>")
		)
		(pad "50" smd rect
			(at 0 41.649904 90)
			(size 1.8034 0.508)
			(layers "F.Cu" "F.Mask" "F.Paste")
			(net "GND")
		)
		(pad "51" smd rect
			(at 0 42.500042 90)
			(size 1.8034 0.508)
			(layers "F.Cu" "F.Mask" "F.Paste")
			(net "M_E_DQS_DP<17>")
		)
		(pad "52" smd rect
			(at 0 43.349926 90)
			(size 1.8034 0.508)
			(layers "F.Cu" "F.Mask" "F.Paste")
			(net "M_E_DQS_DN<17>")
		)
		(pad "53" smd rect
			(at 0 44.200064 90)
			(size 1.8034 0.508)
			(layers "F.Cu" "F.Mask" "F.Paste")
			(net "GND")
		)
		(pad "54" smd rect
			(at 0 45.049948 90)
			(size 1.8034 0.508)
			(layers "F.Cu" "F.Mask" "F.Paste")
			(net "M_E_ECC<7>")
		)
		(pad "55" smd rect
			(at 0 45.900086 90)
			(size 1.8034 0.508)
			(layers "F.Cu" "F.Mask" "F.Paste")
			(net "GND")
		)
		(pad "56" smd rect
			(at 0 46.74997 90)
			(size 1.8034 0.508)
			(layers "F.Cu" "F.Mask" "F.Paste")
			(net "M_E_ECC<3>")
		)
		(pad "57" smd rect
			(at 0 47.600108 90)
			(size 1.8034 0.508)
			(layers "F.Cu" "F.Mask" "F.Paste")
			(net "GND")
		)
		(pad "58" smd rect
			(at 0 48.449992 90)
			(size 1.8034 0.508)
			(layers "F.Cu" "F.Mask" "F.Paste")
			(net "M_DEF_RST_N")
		)
		(pad "59" smd rect
			(at 0 49.299876 90)
			(size 1.8034 0.508)
			(layers "F.Cu" "F.Mask" "F.Paste")
			(net "PVDDQ_DEF")
		)
		(pad "60" smd rect
			(at 0 50.150014 90)
			(size 1.8034 0.508)
			(layers "F.Cu" "F.Mask" "F.Paste")
			(net "M_E_CKE<0>")
		)
		(pad "61" smd rect
			(at 0 50.999898 90)
			(size 1.8034 0.508)
			(layers "F.Cu" "F.Mask" "F.Paste")
			(net "PVDDQ_DEF")
		)
		(pad "62" smd rect
			(at 0 51.850036 90)
			(size 1.8034 0.508)
			(layers "F.Cu" "F.Mask" "F.Paste")
			(net "M_E_ACT_N")
		)
		(pad "63" smd rect
			(at 0 52.69992 90)
			(size 1.8034 0.508)
			(layers "F.Cu" "F.Mask" "F.Paste")
			(net "M_E_BG<0>")
		)
		(pad "64" smd rect
			(at 0 53.550058 90)
			(size 1.8034 0.508)
			(layers "F.Cu" "F.Mask" "F.Paste")
			(net "PVDDQ_DEF")
		)
		(pad "65" smd rect
			(at 0 54.399942 90)
			(size 1.8034 0.508)
			(layers "F.Cu" "F.Mask" "F.Paste")
			(net "M_E_MA<12>")
		)
		(pad "66" smd rect
			(at 0 55.25008 90)
			(size 1.8034 0.508)
			(layers "F.Cu" "F.Mask" "F.Paste")
			(net "M_E_MA<9>")
		)
		(pad "67" smd rect
			(at 0 56.099964 90)
			(size 1.8034 0.508)
			(layers "F.Cu" "F.Mask" "F.Paste")
			(net "PVDDQ_DEF")
		)
		(pad "68" smd rect
			(at 0 56.950102 90)
			(size 1.8034 0.508)
			(layers "F.Cu" "F.Mask" "F.Paste")
			(net "M_E_MA<8>")
		)
		(pad "69" smd rect
			(at 0 57.799986 90)
			(size 1.8034 0.508)
			(layers "F.Cu" "F.Mask" "F.Paste")
			(net "M_E_MA<6>")
		)
		(pad "70" smd rect
			(at 0 58.650124 90)
			(size 1.8034 0.508)
			(layers "F.Cu" "F.Mask" "F.Paste")
			(net "PVDDQ_DEF")
		)
		(pad "71" smd rect
			(at 0 59.500008 90)
			(size 1.8034 0.508)
			(layers "F.Cu" "F.Mask" "F.Paste")
			(net "M_E_MA<3>")
		)
		(pad "72" smd rect
			(at 0 60.349892 90)
			(size 1.8034 0.508)
			(layers "F.Cu" "F.Mask" "F.Paste")
			(net "M_E_MA<1>")
		)
		(pad "73" smd rect
			(at 0 61.20003 90)
			(size 1.8034 0.508)
			(layers "F.Cu" "F.Mask" "F.Paste")
			(net "PVDDQ_DEF")
		)
		(pad "74" smd rect
			(at 0 62.049914 90)
			(size 1.8034 0.508)
			(layers "F.Cu" "F.Mask" "F.Paste")
			(net "M_E_CLK_DP<0>")
		)
		(pad "75" smd rect
			(at 0 62.900052 90)
			(size 1.8034 0.508)
			(layers "F.Cu" "F.Mask" "F.Paste")
			(net "M_E_CLK_DN<0>")
		)
		(pad "76" smd rect
			(at 0 63.749936 90)
			(size 1.8034 0.508)
			(layers "F.Cu" "F.Mask" "F.Paste")
			(net "PVDDQ_DEF")
		)
		(pad "77" smd rect
			(at 0 64.600074 90)
			(size 1.8034 0.508)
			(layers "F.Cu" "F.Mask" "F.Paste")
			(net "PVTT_DEF")
		)
		(pad "78" smd rect
			(at 0 70.550024 90)
			(size 1.8034 0.508)
			(layers "F.Cu" "F.Mask" "F.Paste")
			(net "FM_DIMM_EVENT_COD_N")
		)
		(pad "79" smd rect
			(at 0 71.399908 90)
			(size 1.8034 0.508)
			(layers "F.Cu" "F.Mask" "F.Paste")
			(net "M_E_MA<0>")
		)
		(pad "80" smd rect
			(at 0 72.250046 90)
			(size 1.8034 0.508)
			(layers "F.Cu" "F.Mask" "F.Paste")
			(net "PVDDQ_DEF")
		)
		(pad "81" smd rect
			(at 0 73.09993 90)
			(size 1.8034 0.508)
			(layers "F.Cu" "F.Mask" "F.Paste")
			(net "M_E_BA<0>")
		)
		(pad "82" smd rect
			(at 0 73.950068 90)
			(size 1.8034 0.508)
			(layers "F.Cu" "F.Mask" "F.Paste")
			(net "M_E_MA<16>")
		)
		(pad "83" smd rect
			(at 0 74.799952 90)
			(size 1.8034 0.508)
			(layers "F.Cu" "F.Mask" "F.Paste")
			(net "PVDDQ_DEF")
		)
		(pad "84" smd rect
			(at 0 75.65009 90)
			(size 1.8034 0.508)
			(layers "F.Cu" "F.Mask" "F.Paste")
			(net "M_E_CS_N<0>")
		)
		(pad "85" smd rect
			(at 0 76.499974 90)
			(size 1.8034 0.508)
			(layers "F.Cu" "F.Mask" "F.Paste")
			(net "PVDDQ_DEF")
		)
		(pad "86" smd rect
			(at 0 77.350112 90)
			(size 1.8034 0.508)
			(layers "F.Cu" "F.Mask" "F.Paste")
			(net "M_E_MA<15>")
		)
		(pad "87" smd rect
			(at 0 78.199996 90)
			(size 1.8034 0.508)
			(layers "F.Cu" "F.Mask" "F.Paste")
			(net "M_E_ODT<0>")
		)
		(pad "88" smd rect
			(at 0 79.04988 90)
			(size 1.8034 0.508)
			(layers "F.Cu" "F.Mask" "F.Paste")
			(net "PVDDQ_DEF")
		)
		(pad "89" smd rect
			(at 0 79.900018 90)
			(size 1.8034 0.508)
			(layers "F.Cu" "F.Mask" "F.Paste")
			(net "M_E_CS_N<1>")
		)
		(pad "90" smd rect
			(at 0 80.749902 90)
			(size 1.8034 0.508)
			(layers "F.Cu" "F.Mask" "F.Paste")
			(net "PVDDQ_DEF")
		)
		(pad "91" smd rect
			(at 0 81.60004 90)
			(size 1.8034 0.508)
			(layers "F.Cu" "F.Mask" "F.Paste")
			(net "M_E_ODT<1>")
		)
		(pad "92" smd rect
			(at 0 82.449924 90)
			(size 1.8034 0.508)
			(layers "F.Cu" "F.Mask" "F.Paste")
			(net "PVDDQ_DEF")
		)
		(pad "93" smd rect
			(at 0 83.300062 90)
			(size 1.8034 0.508)
			(layers "F.Cu" "F.Mask" "F.Paste")
			(net "M_E_CS_N<2>")
		)
		(pad "94" smd rect
			(at 0 84.149946 90)
			(size 1.8034 0.508)
			(layers "F.Cu" "F.Mask" "F.Paste")
			(net "GND")
		)
		(pad "95" smd rect
			(at 0 85.000084 90)
			(size 1.8034 0.508)
			(layers "F.Cu" "F.Mask" "F.Paste")
			(net "M_E_DQ<37>")
		)
		(pad "96" smd rect
			(at 0 85.849968 90)
			(size 1.8034 0.508)
			(layers "F.Cu" "F.Mask" "F.Paste")
			(net "GND")
		)
		(pad "97" smd rect
			(at 0 86.700106 90)
			(size 1.8034 0.508)
			(layers "F.Cu" "F.Mask" "F.Paste")
			(net "M_E_DQ<33>")
		)
		(pad "98" smd rect
			(at 0 87.54999 90)
			(size 1.8034 0.508)
			(layers "F.Cu" "F.Mask" "F.Paste")
			(net "GND")
		)
		(pad "99" smd rect
			(at 0 88.399874 90)
			(size 1.8034 0.508)
			(layers "F.Cu" "F.Mask" "F.Paste")
			(net "M_E_DQS_DP<13>")
		)
		(pad "100" smd rect
			(at 0 89.250012 90)
			(size 1.8034 0.508)
			(layers "F.Cu" "F.Mask" "F.Paste")
			(net "M_E_DQS_DN<13>")
		)
		(pad "101" smd rect
			(at 0 90.099896 90)
			(size 1.8034 0.508)
			(layers "F.Cu" "F.Mask" "F.Paste")
			(net "GND")
		)
		(pad "102" smd rect
			(at 0 90.950034 90)
			(size 1.8034 0.508)
			(layers "F.Cu" "F.Mask" "F.Paste")
			(net "M_E_DQ<39>")
		)
		(pad "103" smd rect
			(at 0 91.799918 90)
			(size 1.8034 0.508)
			(layers "F.Cu" "F.Mask" "F.Paste")
			(net "GND")
		)
		(pad "104" smd rect
			(at 0 92.650056 90)
			(size 1.8034 0.508)
			(layers "F.Cu" "F.Mask" "F.Paste")
			(net "M_E_DQ<35>")
		)
		(pad "105" smd rect
			(at 0 93.49994 90)
			(size 1.8034 0.508)
			(layers "F.Cu" "F.Mask" "F.Paste")
			(net "GND")
		)
		(pad "106" smd rect
			(at 0 94.350078 90)
			(size 1.8034 0.508)
			(layers "F.Cu" "F.Mask" "F.Paste")
			(net "M_E_DQ<45>")
		)
		(pad "107" smd rect
			(at 0 95.199962 90)
			(size 1.8034 0.508)
			(layers "F.Cu" "F.Mask" "F.Paste")
			(net "GND")
		)
		(pad "108" smd rect
			(at 0 96.0501 90)
			(size 1.8034 0.508)
			(layers "F.Cu" "F.Mask" "F.Paste")
			(net "M_E_DQ<41>")
		)
		(pad "109" smd rect
			(at 0 96.899984 90)
			(size 1.8034 0.508)
			(layers "F.Cu" "F.Mask" "F.Paste")
			(net "GND")
		)
		(pad "110" smd rect
			(at 0 97.750122 90)
			(size 1.8034 0.508)
			(layers "F.Cu" "F.Mask" "F.Paste")
			(net "M_E_DQS_DP<14>")
		)
		(pad "111" smd rect
			(at 0 98.600006 90)
			(size 1.8034 0.508)
			(layers "F.Cu" "F.Mask" "F.Paste")
			(net "M_E_DQS_DN<14>")
		)
		(pad "112" smd rect
			(at 0 99.44989 90)
			(size 1.8034 0.508)
			(layers "F.Cu" "F.Mask" "F.Paste")
			(net "GND")
		)
		(pad "113" smd rect
			(at 0 100.300028 90)
			(size 1.8034 0.508)
			(layers "F.Cu" "F.Mask" "F.Paste")
			(net "M_E_DQ<47>")
		)
		(pad "114" smd rect
			(at 0 101.149912 90)
			(size 1.8034 0.508)
			(layers "F.Cu" "F.Mask" "F.Paste")
			(net "GND")
		)
		(pad "115" smd rect
			(at 0 102.00005 90)
			(size 1.8034 0.508)
			(layers "F.Cu" "F.Mask" "F.Paste")
			(net "M_E_DQ<43>")
		)
		(pad "116" smd rect
			(at 0 102.849934 90)
			(size 1.8034 0.508)
			(layers "F.Cu" "F.Mask" "F.Paste")
			(net "GND")
		)
		(pad "117" smd rect
			(at 0 103.700072 90)
			(size 1.8034 0.508)
			(layers "F.Cu" "F.Mask" "F.Paste")
			(net "M_E_DQ<53>")
		)
		(pad "118" smd rect
			(at 0 104.549956 90)
			(size 1.8034 0.508)
			(layers "F.Cu" "F.Mask" "F.Paste")
			(net "GND")
		)
		(pad "119" smd rect
			(at 0 105.400094 90)
			(size 1.8034 0.508)
			(layers "F.Cu" "F.Mask" "F.Paste")
			(net "M_E_DQ<49>")
		)
		(pad "120" smd rect
			(at 0 106.249978 90)
			(size 1.8034 0.508)
			(layers "F.Cu" "F.Mask" "F.Paste")
			(net "GND")
		)
	)
)
